# T6G (Grand Teton) — schematic netlist excerpt (pin names and nets, part order shuffled) for the footprints in the layout excerpt that follows; sources: Cadence DE-HDL packaged netlist, KiCad conversion of 04192023_DAF0TMB3IC0_F0TG_MB_C_brd_V02_OCP.brd

C2512  Q_CAP  10UF 6.3V 20% X6S  pkg C0402  page 71 : A = PVDD_33_S5 ; B = GND

(kicad_pcb
	(version 20260206)
	(generator "pcbnew")
	(generator_version "10.0")
	(general
		(thickness 1.6)
		(legacy_teardrops no)
	)
	(paper "A4")
	(title_block
		(title "04192023_DAF0TMB3IC0_F0TG_MB_C_brd_V02_OCP.brd")
		(comment 1 "Grand Teton / footprints 5389-5389 of 8354")
	)
	(layers
		(0 "F.Cu" signal "TOP")
		(4 "In1.Cu" signal "GND")
		(6 "In2.Cu" signal "IN1")
		(8 "In3.Cu" signal "GND1")
		(10 "In4.Cu" signal "IN2")
		(12 "In5.Cu" signal "GND2")
		(14 "In6.Cu" signal "IN3")
		(16 "In7.Cu" signal "GND3")
		(18 "In8.Cu" signal "VCC")
		(20 "In9.Cu" signal "VCC1")
		(22 "In10.Cu" signal "GND4")
		(24 "In11.Cu" signal "IN4")
		(26 "In12.Cu" signal "GND5")
		(28 "In13.Cu" signal "IN5")
		(30 "In14.Cu" signal "GND6")
		(32 "In15.Cu" signal "IN6")
		(34 "In16.Cu" signal "GND7")
		(2 "B.Cu" signal "BOTTOM")
		(9 "F.Adhes" user "F.Adhesive")
		(11 "B.Adhes" user "B.Adhesive")
		(13 "F.Paste" user "Package Geometry/Pastemask Top")
		(15 "B.Paste" user "Package Geometry/Pastemask Bottom")
		(5 "F.SilkS" user "Ref Des/Silkscreen Top")
		(7 "B.SilkS" user "Ref Des/Silkscreen Bottom")
		(1 "F.Mask" user "Board Geometry/Soldermask Top")
		(3 "B.Mask" user "Board Geometry/Soldermask Bottom")
		(17 "Dwgs.User" user "User.Drawings")
		(19 "Cmts.User" user "User.Comments")
		(21 "Eco1.User" user "User.Eco1")
		(23 "Eco2.User" user "User.Eco2")
		(25 "Edge.Cuts" user "Board Geometry/Outline")
		(27 "Margin" user)
		(31 "F.CrtYd" user "Package Geometry/Place Bound Top")
		(29 "B.CrtYd" user "Package Geometry/Place Bound Bottom")
		(35 "F.Fab" user "Ref Des/Assembly Top")
		(33 "B.Fab" user "Ref Des/Assembly Bottom")
	)
	(footprint ""
		(layer "B.Cu")
		(at 346.913454 -267.52931)
		(property "Reference" "C2512"
			(at 0 0 0)
			(layer "B.SilkS")
			(hide yes)
			(effects
				(font
					(size 1.27 1.27)
				)
				(justify mirror)
			)
		)
		(property "Value" ""
			(at 0 0 0)
			(layer "B.Fab")
			(effects
				(font
					(size 1.27 1.27)
				)
				(justify mirror)
			)
		)
		(duplicate_pad_numbers_are_jumpers no)
		(fp_line
			(start -0.7874 -0.4064)
			(end -0.7874 0.4064)
			(stroke
				(width 0.1524)
				(type default)
			)
			(layer "B.SilkS")
		)
		(fp_line
			(start -0.7874 0.4064)
			(end 0.7874 0.4064)
			(stroke
				(width 0.1524)
				(type default)
			)
			(layer "B.SilkS")
		)
		(fp_line
			(start 0.7874 -0.4064)
			(end -0.7874 -0.4064)
			(stroke
				(width 0.1524)
				(type default)
			)
			(layer "B.SilkS")
		)
		(fp_line
			(start 0.7874 0.4064)
			(end 0.7874 -0.4064)
			(stroke
				(width 0.1524)
				(type default)
			)
			(layer "B.SilkS")
		)
		(fp_line
			(start -0.67945 -0.3048)
			(end -0.67945 0.3048)
			(stroke
				(width 0.1)
				(type default)
			)
			(layer "B.Fab")
		)
		(fp_line
			(start -0.67945 0.3048)
			(end -0.120396 0.3048)
			(stroke
				(width 0.1)
				(type default)
			)
			(layer "B.Fab")
		)
		(fp_line
			(start -0.12065 -0.3048)
			(end -0.67945 -0.3048)
			(stroke
				(width 0.1)
				(type default)
			)
			(layer "B.Fab")
		)
		(fp_line
			(start -0.12065 -0.2794)
			(end -0.12065 -0.3048)
			(stroke
				(width 0.1)
				(type default)
			)
			(layer "B.Fab")
		)
		(fp_line
			(start -0.120396 0.2794)
			(end 0.12065 0.2794)
			(stroke
				(width 0.1)
				(type default)
			)
			(layer "B.Fab")
		)
		(fp_line
			(start -0.120396 0.3048)
			(end -0.120396 0.2794)
			(stroke
				(width 0.1)
				(type default)
			)
			(layer "B.Fab")
		)
		(fp_line
			(start 0.12065 -0.305054)
			(end 0.12065 -0.2794)
			(stroke
				(width 0.1)
				(type default)
			)
			(layer "B.Fab")
		)
		(fp_line
			(start 0.12065 -0.2794)
			(end -0.12065 -0.2794)
			(stroke
				(width 0.1)
				(type default)
			)
			(layer "B.Fab")
		)
		(fp_line
			(start 0.12065 0.2794)
			(end 0.12065 0.3048)
			(stroke
				(width 0.1)
				(type default)
			)
			(layer "B.Fab")
		)
		(fp_line
			(start 0.12065 0.3048)
			(end 0.67945 0.3048)
			(stroke
				(width 0.1)
				(type default)
			)
			(layer "B.Fab")
		)
		(fp_line
			(start 0.67945 -0.305054)
			(end 0.12065 -0.305054)
			(stroke
				(width 0.1)
				(type default)
			)
			(layer "B.Fab")
		)
		(fp_line
			(start 0.67945 0.3048)
			(end 0.67945 -0.305054)
			(stroke
				(width 0.1)
				(type default)
			)
			(layer "B.Fab")
		)
		(pad "1" smd circle
			(at 0.40005 0 180)
			(size 0 0)
			(layers "B.Cu" "B.Mask" "B.Paste")
			(net "PVDD_33_S5")
		)
		(pad "2" smd circle
			(at -0.40005 0 180)
			(size 0 0)
			(layers "B.Cu" "B.Mask" "B.Paste")
			(net "GND")
		)
	)
)
